(kicad_pcb
	(version 20260206)
	(generator "pcbnew")
	(generator_version "10.0")
	(general
		(thickness 1.6)
		(legacy_teardrops no)
	)
	(paper "A4")
	(title_block
		(title "Bryce Canyon_F.DPB_16315-1-OCP.brd")
		(comment 1 "Bryce Canyon / footprints 96-101 of 2223")
	)
	(layers
		(0 "F.Cu" signal "TOP")
		(4 "In1.Cu" signal "L2GND")
		(6 "In2.Cu" signal "L3")
		(8 "In3.Cu" signal "L4GND")
		(10 "In4.Cu" signal "L5")
		(12 "In5.Cu" signal "L6VCC")
		(14 "In6.Cu" signal "L7VCC")
		(16 "In7.Cu" signal "L8")
		(18 "In8.Cu" signal "L9GND")
		(20 "In9.Cu" signal "L10")
		(22 "In10.Cu" signal "L11GND")
		(2 "B.Cu" signal "BOTTOM")
		(9 "F.Adhes" user "F.Adhesive")
		(11 "B.Adhes" user "B.Adhesive")
		(13 "F.Paste" user "Package Geometry/Pastemask Top")
		(15 "B.Paste" user "Package Geometry/Pastemask Bottom")
		(5 "F.SilkS" user "Ref Des/Silkscreen Top")
		(7 "B.SilkS" user "Ref Des/Silkscreen Bottom")
		(1 "F.Mask" user "Board Geometry/Soldermask Top")
		(3 "B.Mask" user "Board Geometry/Soldermask Bottom")
		(17 "Dwgs.User" user "User.Drawings")
		(19 "Cmts.User" user "User.Comments")
		(21 "Eco1.User" user "User.Eco1")
		(23 "Eco2.User" user "User.Eco2")
		(25 "Edge.Cuts" user "Board Geometry/Outline")
		(27 "Margin" user)
		(31 "F.CrtYd" user "Package Geometry/Place Bound Top")
		(29 "B.CrtYd" user "Package Geometry/Place Bound Bottom")
		(35 "F.Fab" user "Ref Des/Assembly Top")
		(33 "B.Fab" user "Ref Des/Assembly Bottom")
	)
	(footprint ""
		(layer "F.Cu")
		(at 149.196298 -161.040318 -90)
		(property "Reference" "R506"
			(at 0 0 270)
			(layer "F.SilkS")
			(hide yes)
			(effects
				(font
					(size 1.27 1.27)
				)
			)
		)
		(property "Value" "1KR2F-3-GP"
			(at 0.064008 -3.993896 270)
			(unlocked yes)
			(layer "F.Fab")
			(hide yes)
			(effects
				(font
					(size 1.016 1.016)
					(thickness 0.1524)
				)
			)
		)
		(property "Device Type" "R402H16"
			(at 0.064008 -5.517896 270)
			(unlocked yes)
			(layer "F.Fab")
			(hide yes)
			(effects
				(font
					(size 1.016 1.016)
					(thickness 0.1524)
				)
			)
		)
		(duplicate_pad_numbers_are_jumpers no)
		(fp_line
			(start -0.508 -0.9398)
			(end -0.508 0.9398)
			(stroke
				(width 0.1524)
				(type default)
			)
			(layer "F.SilkS")
		)
		(fp_line
			(start 0.508 -0.9398)
			(end -0.508 -0.9398)
			(stroke
				(width 0.1524)
				(type default)
			)
			(layer "F.SilkS")
		)
		(fp_rect
			(start -0.508 0.9398)
			(end 0.508 -0.9398)
			(stroke
				(width 0)
				(type default)
			)
			(fill no)
			(layer "F.CrtYd")
		)
		(fp_rect
			(start -0.508 0.9398)
			(end 0.508 -0.9398)
			(stroke
				(width 0)
				(type default)
			)
			(fill no)
			(layer "F.Fab")
		)
		(pad "1" smd custom
			(at 0 -0.4445 270)
			(size 0.1397 0.1397)
			(layers "F.Cu" "F.Mask" "F.Paste")
			(net "P3V3_STBY_A")
			(options
				(clearance outline)
				(anchor circle)
			)
			(primitives
				(gr_poly
					(pts
						(arc
							(start -0.1778 -0.2794)
							(mid -0.249642 -0.249642)
							(end -0.2794 -0.1778)
						)
						(arc
							(start -0.2794 0.1778)
							(mid -0.249642 0.249642)
							(end -0.1778 0.2794)
						)
						(arc
							(start 0.1778 0.2794)
							(mid 0.249642 0.249642)
							(end 0.2794 0.1778)
						)
						(arc
							(start 0.2794 -0.1778)
							(mid 0.249642 -0.249642)
							(end 0.1778 -0.2794)
						)
					)
					(width 0)
					(fill yes)
				)
			)
		)
		(pad "2" smd custom
			(at 0 0.4445 270)
			(size 0.1397 0.1397)
			(layers "F.Cu" "F.Mask" "F.Paste")
			(net "SW_PWR_R_HDD16")
			(options
				(clearance outline)
				(anchor circle)
			)
			(primitives
				(gr_poly
					(pts
						(arc
							(start -0.1778 -0.2794)
							(mid -0.249642 -0.249642)
							(end -0.2794 -0.1778)
						)
						(arc
							(start -0.2794 0.1778)
							(mid -0.249642 0.249642)
							(end -0.1778 0.2794)
						)
						(arc
							(start 0.1778 0.2794)
							(mid 0.249642 0.249642)
							(end 0.2794 0.1778)
						)
						(arc
							(start 0.2794 -0.1778)
							(mid 0.249642 -0.249642)
							(end 0.1778 -0.2794)
						)
					)
					(width 0)
					(fill yes)
				)
			)
		)
	)
	(footprint ""
		(layer "F.Cu")
		(at 399.90395 -177.016918)
		(property "Reference" "Q122"
			(at 0 0 0)
			(layer "F.SilkS")
			(hide yes)
			(effects
				(font
					(size 1.27 1.27)
				)
			)
		)
		(property "Value" "AO4407AL-GP"
			(at -3.707384 -1.5367 0)
			(unlocked yes)
			(layer "F.Fab")
			(hide yes)
			(effects
				(font
					(size 1.016 1.016)
					(thickness 0.1524)
				)
			)
		)
		(property "Device Type" "SOIC8H69"
			(at -3.707384 -3.0607 0)
			(unlocked yes)
			(layer "F.Fab")
			(hide yes)
			(effects
				(font
					(size 1.016 1.016)
					(thickness 0.1524)
				)
			)
		)
		(duplicate_pad_numbers_are_jumpers no)
		(fp_line
			(start -2.7432 -1.4224)
			(end -2.7432 1.4224)
			(stroke
				(width 0.1524)
				(type default)
			)
			(layer "F.SilkS")
		)
		(fp_line
			(start -2.7432 1.4224)
			(end -2.6416 1.4224)
			(stroke
				(width 0.1524)
				(type default)
			)
			(layer "F.SilkS")
		)
		(fp_line
			(start -2.7432 1.4224)
			(end 2.1336 1.4224)
			(stroke
				(width 0.1524)
				(type default)
			)
			(layer "F.SilkS")
		)
		(fp_line
			(start -2.7178 -0.508)
			(end -2.1844 -0.0508)
			(stroke
				(width 0.1524)
				(type default)
			)
			(layer "F.SilkS")
		)
		(fp_line
			(start -2.6289 3.4417)
			(end -2.6289 1.4732)
			(stroke
				(width 0.381)
				(type default)
			)
			(layer "F.SilkS")
		)
		(fp_line
			(start -2.1844 -0.0508)
			(end -2.7178 0.508)
			(stroke
				(width 0.1524)
				(type default)
			)
			(layer "F.SilkS")
		)
		(fp_line
			(start 2.1336 -1.4224)
			(end -2.7432 -1.4224)
			(stroke
				(width 0.1524)
				(type default)
			)
			(layer "F.SilkS")
		)
		(fp_line
			(start 2.1336 1.4224)
			(end 2.1336 -1.4224)
			(stroke
				(width 0.1524)
				(type default)
			)
			(layer "F.SilkS")
		)
		(fp_poly
			(pts
				(xy -2.2098 -1.4224) (xy -2.2098 1.4224) (xy 2.2098 1.4224) (xy 2.2098 -1.4224)
			)
			(stroke
				(width 0)
				(type default)
			)
			(fill yes)
			(layer "F.SilkS")
		)
		(fp_rect
			(start -2.450084 2.999994)
			(end 2.450084 -2.999994)
			(stroke
				(width 0)
				(type default)
			)
			(fill no)
			(layer "F.CrtYd")
		)
		(fp_poly
			(pts
				(xy -2.8194 3.6322) (xy -2.8194 -3.6322) (xy 2.8194 -3.6322) (xy 2.8194 1.18364) (xy 2.450084 1.18364)
				(xy 2.450084 -2.999994) (xy -2.450084 -2.999994) (xy -2.450084 2.999994) (xy 2.450084 2.999994)
				(xy 2.450084 1.18618) (xy 2.8194 1.18618) (xy 2.8194 3.6322)
			)
			(stroke
				(width 0)
				(type default)
			)
			(fill no)
			(layer "F.CrtYd")
		)
		(fp_rect
			(start -2.8194 3.6322)
			(end 2.8194 -3.6322)
			(stroke
				(width 0)
				(type default)
			)
			(fill no)
			(layer "F.Fab")
		)
		(pad "1" smd rect
			(at -1.905 2.54)
			(size 0.635 1.651)
			(layers "F.Cu" "F.Mask" "F.Paste")
			(net "P12V_A")
		)
		(pad "2" smd rect
			(at -0.635 2.54)
			(size 0.635 1.651)
			(layers "F.Cu" "F.Mask" "F.Paste")
			(net "P12V_A")
		)
		(pad "3" smd rect
			(at 0.635 2.54)
			(size 0.635 1.651)
			(layers "F.Cu" "F.Mask" "F.Paste")
			(net "P12V_A")
		)
		(pad "4" smd rect
			(at 1.905 2.54)
			(size 0.635 1.651)
			(layers "F.Cu" "F.Mask" "F.Paste")
			(net "SW_HDD_N20")
		)
		(pad "5" smd rect
			(at 1.905 -2.54)
			(size 0.635 1.651)
			(layers "F.Cu" "F.Mask" "F.Paste")
			(net "P12V_HDD20")
		)
		(pad "6" smd rect
			(at 0.635 -2.54)
			(size 0.635 1.651)
			(layers "F.Cu" "F.Mask" "F.Paste")
			(net "P12V_HDD20")
		)
		(pad "7" smd rect
			(at -0.635 -2.54)
			(size 0.635 1.651)
			(layers "F.Cu" "F.Mask" "F.Paste")
			(net "P12V_HDD20")
		)
		(pad "8" smd rect
			(at -1.905 -2.54)
			(size 0.635 1.651)
			(layers "F.Cu" "F.Mask" "F.Paste")
			(net "P12V_HDD20")
		)
	)
	(footprint ""
		(layer "F.Cu")
		(at 392.91895 -66.842894 180)
		(property "Reference" "C456"
			(at 0 0 180)
			(layer "F.SilkS")
			(hide yes)
			(effects
				(font
					(size 1.27 1.27)
				)
			)
		)
		(property "Value" "SC1U16V3KX-5GP"
			(at 0 -2.8194 180)
			(unlocked yes)
			(layer "F.Fab")
			(hide yes)
			(effects
				(font
					(size 1.016 1.016)
					(thickness 0.1524)
				)
			)
		)
		(property "Device Type" "C603H36"
			(at 0 -4.3434 180)
			(unlocked yes)
			(layer "F.Fab")
			(hide yes)
			(effects
				(font
					(size 1.016 1.016)
					(thickness 0.1524)
				)
			)
		)
		(duplicate_pad_numbers_are_jumpers no)
		(fp_line
			(start 0.508 0)
			(end -0.508 0)
			(stroke
				(width 0.2032)
				(type default)
			)
			(layer "F.SilkS")
		)
		(fp_rect
			(start -0.5842 1.3335)
			(end 0.5842 -1.3335)
			(stroke
				(width 0)
				(type default)
			)
			(fill no)
			(layer "F.CrtYd")
		)
		(fp_rect
			(start -0.5842 1.3335)
			(end 0.5842 -1.3335)
			(stroke
				(width 0)
				(type default)
			)
			(fill no)
			(layer "F.Fab")
		)
		(pad "1" smd custom
			(at 0 -0.762 180)
			(size 0.2159 0.2159)
			(layers "F.Cu" "F.Mask" "F.Paste")
			(net "P5V_HDD32")
			(options
				(clearance outline)
				(anchor circle)
			)
			(primitives
				(gr_poly
					(pts
						(arc
							(start -0.3302 -0.4318)
							(mid -0.402042 -0.402042)
							(end -0.4318 -0.3302)
						)
						(arc
							(start -0.4318 0.3302)
							(mid -0.402042 0.402042)
							(end -0.3302 0.4318)
						)
						(arc
							(start 0.3302 0.4318)
							(mid 0.402042 0.402042)
							(end 0.4318 0.3302)
						)
						(arc
							(start 0.4318 -0.3302)
							(mid 0.402042 -0.402042)
							(end 0.3302 -0.4318)
						)
					)
					(width 0)
					(fill yes)
				)
			)
		)
		(pad "2" smd custom
			(at 0 0.762 180)
			(size 0.2159 0.2159)
			(layers "F.Cu" "F.Mask" "F.Paste")
			(net "GND")
			(options
				(clearance outline)
				(anchor circle)
			)
			(primitives
				(gr_poly
					(pts
						(arc
							(start -0.3302 -0.4318)
							(mid -0.402042 -0.402042)
							(end -0.4318 -0.3302)
						)
						(arc
							(start -0.4318 0.3302)
							(mid -0.402042 0.402042)
							(end -0.3302 0.4318)
						)
						(arc
							(start 0.3302 0.4318)
							(mid 0.402042 0.402042)
							(end 0.4318 0.3302)
						)
						(arc
							(start 0.4318 -0.3302)
							(mid 0.402042 -0.402042)
							(end 0.3302 -0.4318)
						)
					)
					(width 0)
					(fill yes)
				)
			)
		)
	)
	(footprint ""
		(layer "F.Cu")
		(at 132.6769 -188.896244)
		(property "Reference" "Q231"
			(at 0 0 0)
			(layer "F.SilkS")
			(hide yes)
			(effects
				(font
					(size 1.27 1.27)
				)
			)
		)
		(property "Value" "2N7002K-2-GP"
			(at 0.127 -8.9662 0)
			(unlocked yes)
			(layer "F.Fab")
			(hide yes)
			(effects
				(font
					(size 1.016 1.016)
					(thickness 0.1524)
				)
			)
		)
		(property "Device Type" "SOT23DGS2D4H44"
			(at 0.127 -10.4902 0)
			(unlocked yes)
			(layer "F.Fab")
			(hide yes)
			(effects
				(font
					(size 1.016 1.016)
					(thickness 0.1524)
				)
			)
		)
		(duplicate_pad_numbers_are_jumpers no)
		(fp_line
			(start -1.651 -1.778)
			(end -1.651 1.778)
			(stroke
				(width 0.1524)
				(type default)
			)
			(layer "F.SilkS")
		)
		(fp_line
			(start -1.651 1.778)
			(end 1.651 1.778)
			(stroke
				(width 0.1524)
				(type default)
			)
			(layer "F.SilkS")
		)
		(fp_line
			(start 1.651 -1.778)
			(end -1.651 -1.778)
			(stroke
				(width 0.1524)
				(type default)
			)
			(layer "F.SilkS")
		)
		(fp_line
			(start 1.651 1.778)
			(end 1.651 -1.778)
			(stroke
				(width 0.1524)
				(type default)
			)
			(layer "F.SilkS")
		)
		(fp_poly
			(pts
				(xy -1.778 1.8796) (xy -1.778 -1.8796) (xy 1.778 -1.8796) (xy 1.778 1.8796)
			)
			(stroke
				(width 0)
				(type default)
			)
			(fill no)
			(layer "F.CrtYd")
		)
		(fp_poly
			(pts
				(xy -1.778 1.8796) (xy -1.778 -1.8796) (xy 1.778 -1.8796) (xy 1.778 1.8796)
			)
			(stroke
				(width 0)
				(type default)
			)
			(fill no)
			(layer "F.Fab")
		)
		(pad "D" smd custom
			(at 0 -0.9525)
			(size 0.1905 0.1905)
			(layers "F.Cu" "F.Mask" "F.Paste")
			(net "FLT_HDD4_N")
			(options
				(clearance outline)
				(anchor circle)
			)
			(primitives
				(gr_poly
					(pts
						(arc
							(start -0.1778 0.5715)
							(mid -0.321484 0.511984)
							(end -0.381 0.3683)
						)
						(arc
							(start -0.381 -0.3683)
							(mid -0.321484 -0.511984)
							(end -0.1778 -0.5715)
						)
						(arc
							(start 0.1778 -0.5715)
							(mid 0.321484 -0.511984)
							(end 0.381 -0.3683)
						)
						(arc
							(start 0.381 0.3683)
							(mid 0.321484 0.511984)
							(end 0.1778 0.5715)
						)
					)
					(width 0)
					(fill yes)
				)
			)
		)
		(pad "G" smd custom
			(at -0.98425 0.9525)
			(size 0.1905 0.1905)
			(layers "F.Cu" "F.Mask" "F.Paste")
			(net "DRIVE_A_4_FLT_LED")
			(options
				(clearance outline)
				(anchor circle)
			)
			(primitives
				(gr_poly
					(pts
						(arc
							(start -0.1778 0.5715)
							(mid -0.321484 0.511984)
							(end -0.381 0.3683)
						)
						(arc
							(start -0.381 -0.3683)
							(mid -0.321484 -0.511984)
							(end -0.1778 -0.5715)
						)
						(arc
							(start 0.1778 -0.5715)
							(mid 0.321484 -0.511984)
							(end 0.381 -0.3683)
						)
						(arc
							(start 0.381 0.3683)
							(mid 0.321484 0.511984)
							(end 0.1778 0.5715)
						)
					)
					(width 0)
					(fill yes)
				)
			)
		)
		(pad "S" smd custom
			(at 0.98425 0.9525)
			(size 0.1905 0.1905)
			(layers "F.Cu" "F.Mask" "F.Paste")
			(net "GND")
			(options
				(clearance outline)
				(anchor circle)
			)
			(primitives
				(gr_poly
					(pts
						(arc
							(start -0.1778 0.5715)
							(mid -0.321484 0.511984)
							(end -0.381 0.3683)
						)
						(arc
							(start -0.381 -0.3683)
							(mid -0.321484 -0.511984)
							(end -0.1778 -0.5715)
						)
						(arc
							(start 0.1778 -0.5715)
							(mid 0.321484 -0.511984)
							(end 0.381 -0.3683)
						)
						(arc
							(start 0.381 0.3683)
							(mid 0.321484 0.511984)
							(end 0.1778 0.5715)
						)
					)
					(width 0)
					(fill yes)
				)
			)
		)
	)
	(footprint ""
		(layer "F.Cu")
		(at 235.7374 -231.3178)
		(property "Reference" "R71"
			(at 0 0 0)
			(layer "F.SilkS")
			(hide yes)
			(effects
				(font
					(size 1.27 1.27)
				)
			)
		)
		(property "Value" "0R2J-2-GP"
			(at 0.064008 -3.993896 0)
			(unlocked yes)
			(layer "F.Fab")
			(hide yes)
			(effects
				(font
					(size 1.016 1.016)
					(thickness 0.1524)
				)
			)
		)
		(property "Device Type" "R402H16"
			(at 0.064008 -5.517896 0)
			(unlocked yes)
			(layer "F.Fab")
			(hide yes)
			(effects
				(font
					(size 1.016 1.016)
					(thickness 0.1524)
				)
			)
		)
		(duplicate_pad_numbers_are_jumpers no)
		(fp_line
			(start -0.508 -0.9398)
			(end -0.508 0.9398)
			(stroke
				(width 0.1524)
				(type default)
			)
			(layer "F.SilkS")
		)
		(fp_line
			(start 0.508 -0.9398)
			(end -0.508 -0.9398)
			(stroke
				(width 0.1524)
				(type default)
			)
			(layer "F.SilkS")
		)
		(fp_rect
			(start -0.508 0.9398)
			(end 0.508 -0.9398)
			(stroke
				(width 0)
				(type default)
			)
			(fill no)
			(layer "F.CrtYd")
		)
		(fp_rect
			(start -0.508 0.9398)
			(end 0.508 -0.9398)
			(stroke
				(width 0)
				(type default)
			)
			(fill no)
			(layer "F.Fab")
		)
		(pad "1" smd custom
			(at 0 -0.4445)
			(size 0.1397 0.1397)
			(layers "F.Cu" "F.Mask" "F.Paste")
			(net "IO_EXP1_SDA")
			(options
				(clearance outline)
				(anchor circle)
			)
			(primitives
				(gr_poly
					(pts
						(arc
							(start -0.1778 -0.2794)
							(mid -0.249642 -0.249642)
							(end -0.2794 -0.1778)
						)
						(arc
							(start -0.2794 0.1778)
							(mid -0.249642 0.249642)
							(end -0.1778 0.2794)
						)
						(arc
							(start 0.1778 0.2794)
							(mid 0.249642 0.249642)
							(end 0.2794 0.1778)
						)
						(arc
							(start 0.2794 -0.1778)
							(mid 0.249642 -0.249642)
							(end 0.1778 -0.2794)
						)
					)
					(width 0)
					(fill yes)
				)
			)
		)
		(pad "2" smd custom
			(at 0 0.4445)
			(size 0.1397 0.1397)
			(layers "F.Cu" "F.Mask" "F.Paste")
			(net "I2C_DRIVE_A_PWR_SDA")
			(options
				(clearance outline)
				(anchor circle)
			)
			(primitives
				(gr_poly
					(pts
						(arc
							(start -0.1778 -0.2794)
							(mid -0.249642 -0.249642)
							(end -0.2794 -0.1778)
						)
						(arc
							(start -0.2794 0.1778)
							(mid -0.249642 0.249642)
							(end -0.1778 0.2794)
						)
						(arc
							(start 0.1778 0.2794)
							(mid 0.249642 0.249642)
							(end 0.2794 0.1778)
						)
						(arc
							(start 0.2794 -0.1778)
							(mid 0.249642 -0.249642)
							(end 0.1778 -0.2794)
						)
					)
					(width 0)
					(fill yes)
				)
			)
		)
	)
	(footprint ""
		(layer "F.Cu")
		(at 458.5589 -295.826942 180)
		(property "Reference" "C171"
			(at 0 0 180)
			(layer "F.SilkS")
			(hide yes)
			(effects
				(font
					(size 1.27 1.27)
				)
			)
		)
		(property "Value" "SC10U16V6KX-2GP"
			(at -0.0762 -5.1308 180)
			(unlocked yes)
			(layer "F.Fab")
			(hide yes)
			(effects
				(font
					(size 1.016 1.016)
					(thickness 0.1524)
				)
			)
		)
		(property "Device Type" "C1206H71"
			(at -0.127 -6.6548 180)
			(unlocked yes)
			(layer "F.Fab")
			(hide yes)
			(effects
				(font
					(size 1.016 1.016)
					(thickness 0.1524)
				)
			)
		)
		(duplicate_pad_numbers_are_jumpers no)
		(fp_line
			(start 1.016 2.2352)
			(end -1.016 2.2352)
			(stroke
				(width 0.1524)
				(type default)
			)
			(layer "F.SilkS")
		)
		(fp_line
			(start 1.016 0.8382)
			(end 1.016 2.2352)
			(stroke
				(width 0.1524)
				(type default)
			)
			(layer "F.SilkS")
		)
		(fp_line
			(start 1.016 -2.2352)
			(end 1.016 -0.8382)
			(stroke
				(width 0.1524)
				(type default)
			)
			(layer "F.SilkS")
		)
		(fp_line
			(start -1.016 2.2352)
			(end -1.016 0.8382)
			(stroke
				(width 0.1524)
				(type default)
			)
			(layer "F.SilkS")
		)
		(fp_line
			(start -1.016 -0.8382)
			(end -1.016 -2.2352)
			(stroke
				(width 0.1524)
				(type default)
			)
			(layer "F.SilkS")
		)
		(fp_line
			(start -1.016 -2.2352)
			(end 1.016 -2.2352)
			(stroke
				(width 0.1524)
				(type default)
			)
			(layer "F.SilkS")
		)
		(fp_rect
			(start -1.0922 2.3114)
			(end 1.0922 -2.3114)
			(stroke
				(width 0)
				(type default)
			)
			(fill no)
			(layer "F.CrtYd")
		)
		(fp_poly
			(pts
				(xy 1.0922 -2.3114) (xy 1.0922 2.3114) (xy -1.0922 2.3114) (xy -1.0922 -2.3114)
			)
			(stroke
				(width 0)
				(type default)
			)
			(fill no)
			(layer "F.Fab")
		)
		(pad "1" smd rect
			(at 0 -1.397 180)
			(size 1.651 1.27)
			(layers "F.Cu" "F.Mask" "F.Paste")
			(net "P5V_HDD10")
		)
		(pad "2" smd rect
			(at 0 1.397 180)
			(size 1.651 1.27)
			(layers "F.Cu" "F.Mask" "F.Paste")
			(net "GND")
		)
	)
)
